(kicad_pcb
	(version 20260206)
	(generator "pcbnew")
	(generator_version "10.0")
	(general
		(thickness 1.6)
		(legacy_teardrops no)
	)
	(paper "A4")
	(title_block
		(title "peb — Lightning_PEB_BRD.brd")
		(comment 1 "Lightning (Wiwynn / Facebook NVMe JBOF) / footprints 2037-2044 of 2563")
	)
	(layers
		(0 "F.Cu" signal "TOP")
		(4 "In1.Cu" signal "L2GND")
		(6 "In2.Cu" signal "L3")
		(8 "In3.Cu" signal "L4VCC")
		(10 "In4.Cu" signal "L5VCC")
		(12 "In5.Cu" signal "L6")
		(14 "In6.Cu" signal "L7GND")
		(2 "B.Cu" signal "BOTTOM")
		(9 "F.Adhes" user "F.Adhesive")
		(11 "B.Adhes" user "B.Adhesive")
		(13 "F.Paste" user "Package Geometry/Pastemask Top")
		(15 "B.Paste" user "Package Geometry/Pastemask Bottom")
		(5 "F.SilkS" user "Ref Des/Silkscreen Top")
		(7 "B.SilkS" user "Ref Des/Silkscreen Bottom")
		(1 "F.Mask" user "Board Geometry/Soldermask Top")
		(3 "B.Mask" user "Board Geometry/Soldermask Bottom")
		(17 "Dwgs.User" user "User.Drawings")
		(19 "Cmts.User" user "User.Comments")
		(21 "Eco1.User" user "User.Eco1")
		(23 "Eco2.User" user "User.Eco2")
		(25 "Edge.Cuts" user "Board Geometry/Outline")
		(27 "Margin" user)
		(31 "F.CrtYd" user "Package Geometry/Place Bound Top")
		(29 "B.CrtYd" user "Package Geometry/Place Bound Bottom")
		(35 "F.Fab" user "Ref Des/Assembly Top")
		(33 "B.Fab" user "Ref Des/Assembly Bottom")
	)
	(footprint ""
		(layer "B.Cu")
		(at 328.549 -70.104 180)
		(property "Reference" "PR155"
			(at 0 0 0)
			(layer "B.SilkS")
			(hide yes)
			(effects
				(font
					(size 1.27 1.27)
				)
				(justify mirror)
			)
		)
		(property "Value" "2K21R2F-GP"
			(at -0.064008 -3.993896 180)
			(unlocked yes)
			(layer "B.Fab")
			(hide yes)
			(effects
				(font
					(size 1.016 1.016)
					(thickness 0.1524)
				)
				(justify mirror)
			)
		)
		(property "Device Type" "R402H16"
			(at -0.064008 -5.517896 180)
			(unlocked yes)
			(layer "B.Fab")
			(hide yes)
			(effects
				(font
					(size 1.016 1.016)
					(thickness 0.1524)
				)
				(justify mirror)
			)
		)
		(duplicate_pad_numbers_are_jumpers no)
		(fp_line
			(start 0.508 -0.9398)
			(end 0.508 0.9398)
			(stroke
				(width 0.1524)
				(type default)
			)
			(layer "B.SilkS")
		)
		(fp_line
			(start -0.508 -0.9398)
			(end 0.508 -0.9398)
			(stroke
				(width 0.1524)
				(type default)
			)
			(layer "B.SilkS")
		)
		(fp_rect
			(start 0.508 0.9398)
			(end -0.508 -0.9398)
			(stroke
				(width 0)
				(type default)
			)
			(fill no)
			(layer "B.CrtYd")
		)
		(fp_rect
			(start 0.508 0.9398)
			(end -0.508 -0.9398)
			(stroke
				(width 0)
				(type default)
			)
			(fill no)
			(layer "B.Fab")
		)
		(pad "1" smd custom
			(at 0 -0.4445)
			(size 0.1397 0.1397)
			(layers "B.Cu" "B.Mask" "B.Paste")
			(net "P0V9_E_LX")
			(options
				(clearance outline)
				(anchor circle)
			)
			(primitives
				(gr_poly
					(pts
						(arc
							(start -0.1778 0.2794)
							(mid -0.249642 0.249642)
							(end -0.2794 0.1778)
						)
						(arc
							(start -0.2794 -0.1778)
							(mid -0.249642 -0.249642)
							(end -0.1778 -0.2794)
						)
						(arc
							(start 0.1778 -0.2794)
							(mid 0.249642 -0.249642)
							(end 0.2794 -0.1778)
						)
						(arc
							(start 0.2794 0.1778)
							(mid 0.249642 0.249642)
							(end 0.1778 0.2794)
						)
					)
					(width 0)
					(fill yes)
				)
			)
		)
		(pad "2" smd custom
			(at 0 0.4445)
			(size 0.1397 0.1397)
			(layers "B.Cu" "B.Mask" "B.Paste")
			(net "P0V9_E_SW_R")
			(options
				(clearance outline)
				(anchor circle)
			)
			(primitives
				(gr_poly
					(pts
						(arc
							(start -0.1778 0.2794)
							(mid -0.249642 0.249642)
							(end -0.2794 0.1778)
						)
						(arc
							(start -0.2794 -0.1778)
							(mid -0.249642 -0.249642)
							(end -0.1778 -0.2794)
						)
						(arc
							(start 0.1778 -0.2794)
							(mid 0.249642 -0.249642)
							(end 0.2794 -0.1778)
						)
						(arc
							(start 0.2794 0.1778)
							(mid 0.249642 0.249642)
							(end 0.1778 0.2794)
						)
					)
					(width 0)
					(fill yes)
				)
			)
		)
	)
	(footprint ""
		(layer "B.Cu")
		(at 9.144 -78.3082 -90)
		(property "Reference" "C430"
			(at 0 0 90)
			(layer "B.SilkS")
			(hide yes)
			(effects
				(font
					(size 1.27 1.27)
				)
				(justify mirror)
			)
		)
		(property "Value" "SC10U6D3V5KX-4GP"
			(at 0.0762 -6.1214 270)
			(unlocked yes)
			(layer "B.Fab")
			(hide yes)
			(effects
				(font
					(size 1.016 1.016)
					(thickness 0.1524)
				)
				(justify mirror)
			)
		)
		(property "Device Type" "C805H58"
			(at 0.0762 -8.1534 270)
			(unlocked yes)
			(layer "B.Fab")
			(hide yes)
			(effects
				(font
					(size 1.016 1.016)
					(thickness 0.1524)
				)
				(justify mirror)
			)
		)
		(duplicate_pad_numbers_are_jumpers no)
		(fp_line
			(start -0.635 0)
			(end 0.635 0)
			(stroke
				(width 0.508)
				(type default)
			)
			(layer "B.SilkS")
		)
		(fp_rect
			(start 0.9652 1.778)
			(end -0.9652 -1.778)
			(stroke
				(width 0)
				(type default)
			)
			(fill no)
			(layer "B.CrtYd")
		)
		(fp_poly
			(pts
				(xy 0.9652 -1.778) (xy -0.9652 -1.778) (xy -0.9652 1.778) (xy 0.9652 1.778)
			)
			(stroke
				(width 0)
				(type default)
			)
			(fill no)
			(layer "B.Fab")
		)
		(pad "1" smd rect
			(at 0 -0.9652 90)
			(size 1.397 1.143)
			(layers "B.Cu" "B.Mask" "B.Paste")
			(net "P1V5_I210")
		)
		(pad "2" smd rect
			(at 0 0.9652 90)
			(size 1.397 1.143)
			(layers "B.Cu" "B.Mask" "B.Paste")
			(net "GND")
		)
	)
	(footprint ""
		(layer "B.Cu")
		(at 249.612912 -32.004)
		(property "Reference" "C469"
			(at 0 0 0)
			(layer "B.SilkS")
			(hide yes)
			(effects
				(font
					(size 1.27 1.27)
				)
				(justify mirror)
			)
		)
		(property "Value" "SCD1U16V1KX-1-GP"
			(at 2.8321 -1.7399 0)
			(unlocked yes)
			(layer "B.Fab")
			(hide yes)
			(effects
				(font
					(size 1.016 1.016)
					(thickness 0.1524)
				)
				(justify mirror)
			)
		)
		(property "Device Type" "C0201H13"
			(at 2.8321 -3.2639 0)
			(unlocked yes)
			(layer "B.Fab")
			(hide yes)
			(effects
				(font
					(size 1.016 1.016)
					(thickness 0.1524)
				)
				(justify mirror)
			)
		)
		(duplicate_pad_numbers_are_jumpers no)
		(fp_rect
			(start 0.2794 0.6477)
			(end -0.2794 -0.6477)
			(stroke
				(width 0)
				(type default)
			)
			(fill no)
			(layer "B.CrtYd")
		)
		(fp_rect
			(start 0.2794 0.6477)
			(end -0.2794 -0.6477)
			(stroke
				(width 0)
				(type default)
			)
			(fill no)
			(layer "B.Fab")
		)
		(pad "1" smd custom
			(at 0 -0.2794 180)
			(size 0.0762 0.0762)
			(layers "B.Cu" "B.Mask" "B.Paste")
			(net "DUT_VDDO")
			(options
				(clearance outline)
				(anchor circle)
			)
			(primitives
				(gr_poly
					(pts
						(arc
							(start 0.1524 0.127)
							(mid 0.137521 0.162921)
							(end 0.1016 0.1778)
						)
						(arc
							(start -0.1016 0.1778)
							(mid -0.137521 0.162921)
							(end -0.1524 0.127)
						)
						(arc
							(start -0.1524 -0.127)
							(mid -0.137521 -0.162921)
							(end -0.1016 -0.1778)
						)
						(arc
							(start 0.1016 -0.1778)
							(mid 0.137521 -0.162921)
							(end 0.1524 -0.127)
						)
					)
					(width 0)
					(fill yes)
				)
			)
		)
		(pad "2" smd custom
			(at 0 0.2794 180)
			(size 0.0762 0.0762)
			(layers "B.Cu" "B.Mask" "B.Paste")
			(net "GND")
			(options
				(clearance outline)
				(anchor circle)
			)
			(primitives
				(gr_poly
					(pts
						(arc
							(start 0.1524 0.127)
							(mid 0.137521 0.162921)
							(end 0.1016 0.1778)
						)
						(arc
							(start -0.1016 0.1778)
							(mid -0.137521 0.162921)
							(end -0.1524 0.127)
						)
						(arc
							(start -0.1524 -0.127)
							(mid -0.137521 -0.162921)
							(end -0.1016 -0.1778)
						)
						(arc
							(start 0.1016 -0.1778)
							(mid 0.137521 -0.162921)
							(end 0.1524 -0.127)
						)
					)
					(width 0)
					(fill yes)
				)
			)
		)
	)
	(footprint ""
		(layer "B.Cu")
		(at 219.686124 -190.601092)
		(property "Reference" "R4146"
			(at 0 0 0)
			(layer "B.SilkS")
			(hide yes)
			(effects
				(font
					(size 1.27 1.27)
				)
				(justify mirror)
			)
		)
		(property "Value" "4K7R2F-GP"
			(at -0.064008 -3.993896 0)
			(unlocked yes)
			(layer "B.Fab")
			(hide yes)
			(effects
				(font
					(size 1.016 1.016)
					(thickness 0.1524)
				)
				(justify mirror)
			)
		)
		(property "Device Type" "R402H16"
			(at -0.064008 -5.517896 0)
			(unlocked yes)
			(layer "B.Fab")
			(hide yes)
			(effects
				(font
					(size 1.016 1.016)
					(thickness 0.1524)
				)
				(justify mirror)
			)
		)
		(duplicate_pad_numbers_are_jumpers no)
		(fp_line
			(start -0.508 -0.9398)
			(end 0.508 -0.9398)
			(stroke
				(width 0.1524)
				(type default)
			)
			(layer "B.SilkS")
		)
		(fp_line
			(start 0.508 -0.9398)
			(end 0.508 0.9398)
			(stroke
				(width 0.1524)
				(type default)
			)
			(layer "B.SilkS")
		)
		(fp_rect
			(start 0.508 0.9398)
			(end -0.508 -0.9398)
			(stroke
				(width 0)
				(type default)
			)
			(fill no)
			(layer "B.CrtYd")
		)
		(fp_rect
			(start 0.508 0.9398)
			(end -0.508 -0.9398)
			(stroke
				(width 0)
				(type default)
			)
			(fill no)
			(layer "B.Fab")
		)
		(pad "1" smd custom
			(at 0 -0.4445 180)
			(size 0.1397 0.1397)
			(layers "B.Cu" "B.Mask" "B.Paste")
			(net "SSD_PRSNT#3")
			(options
				(clearance outline)
				(anchor circle)
			)
			(primitives
				(gr_poly
					(pts
						(arc
							(start -0.1778 0.2794)
							(mid -0.249642 0.249642)
							(end -0.2794 0.1778)
						)
						(arc
							(start -0.2794 -0.1778)
							(mid -0.249642 -0.249642)
							(end -0.1778 -0.2794)
						)
						(arc
							(start 0.1778 -0.2794)
							(mid 0.249642 -0.249642)
							(end 0.2794 -0.1778)
						)
						(arc
							(start 0.2794 0.1778)
							(mid 0.249642 0.249642)
							(end 0.1778 0.2794)
						)
					)
					(width 0)
					(fill yes)
				)
			)
		)
		(pad "2" smd custom
			(at 0 0.4445 180)
			(size 0.1397 0.1397)
			(layers "B.Cu" "B.Mask" "B.Paste")
			(net "P3V3_STBY")
			(options
				(clearance outline)
				(anchor circle)
			)
			(primitives
				(gr_poly
					(pts
						(arc
							(start -0.1778 0.2794)
							(mid -0.249642 0.249642)
							(end -0.2794 0.1778)
						)
						(arc
							(start -0.2794 -0.1778)
							(mid -0.249642 -0.249642)
							(end -0.1778 -0.2794)
						)
						(arc
							(start 0.1778 -0.2794)
							(mid 0.249642 -0.249642)
							(end 0.2794 -0.1778)
						)
						(arc
							(start 0.2794 0.1778)
							(mid 0.249642 0.249642)
							(end 0.1778 0.2794)
						)
					)
					(width 0)
					(fill yes)
				)
			)
		)
	)
	(footprint ""
		(layer "B.Cu")
		(at 332.796388 -178.681126)
		(property "Reference" "U68"
			(at 0 0 0)
			(layer "B.SilkS")
			(hide yes)
			(effects
				(font
					(size 1.27 1.27)
				)
				(justify mirror)
			)
		)
		(property "Value" "SN74LVC1G08DCKR-GP"
			(at 2.3368 -8.6868 0)
			(unlocked yes)
			(layer "B.Fab")
			(hide yes)
			(effects
				(font
					(size 1.016 1.016)
					(thickness 0.1524)
				)
				(justify mirror)
			)
		)
		(property "Device Type" "SC70-5H44"
			(at 2.3114 -10.414 0)
			(unlocked yes)
			(layer "B.Fab")
			(hide yes)
			(effects
				(font
					(size 1.016 1.016)
					(thickness 0.1524)
				)
				(justify mirror)
			)
		)
		(duplicate_pad_numbers_are_jumpers no)
		(fp_line
			(start -1.3843 -1.8034)
			(end -1.3843 -1.1176)
			(stroke
				(width 0.3302)
				(type default)
			)
			(layer "B.SilkS")
		)
		(fp_line
			(start -1.27 -1.7018)
			(end -1.27 1.7018)
			(stroke
				(width 0.1524)
				(type default)
			)
			(layer "B.SilkS")
		)
		(fp_line
			(start -1.27 1.7018)
			(end 1.27 1.7018)
			(stroke
				(width 0.1524)
				(type default)
			)
			(layer "B.SilkS")
		)
		(fp_line
			(start -0.6604 -1.8034)
			(end -1.3843 -1.8034)
			(stroke
				(width 0.3302)
				(type default)
			)
			(layer "B.SilkS")
		)
		(fp_line
			(start 1.27 -1.7018)
			(end -1.27 -1.7018)
			(stroke
				(width 0.1524)
				(type default)
			)
			(layer "B.SilkS")
		)
		(fp_line
			(start 1.27 1.7018)
			(end 1.27 -1.7018)
			(stroke
				(width 0.1524)
				(type default)
			)
			(layer "B.SilkS")
		)
		(fp_rect
			(start 1.524 1.9558)
			(end -1.524 -1.9558)
			(stroke
				(width 0)
				(type default)
			)
			(fill no)
			(layer "B.CrtYd")
		)
		(fp_poly
			(pts
				(xy 1.524 -1.9558) (xy -1.524 -1.9558) (xy -1.524 1.9558) (xy 1.524 1.9558)
			)
			(stroke
				(width 0)
				(type default)
			)
			(fill no)
			(layer "B.Fab")
		)
		(pad "1" smd rect
			(at -0.65024 -0.8255 180)
			(size 0.4064 1.2192)
			(layers "B.Cu" "B.Mask" "B.Paste")
			(net "BMC_SSD_RST#0_A4")
		)
		(pad "2" smd rect
			(at 0 -0.8255 180)
			(size 0.4064 1.2192)
			(layers "B.Cu" "B.Mask" "B.Paste")
			(net "SSD_PERST#0_B4")
		)
		(pad "3" smd rect
			(at 0.65024 -0.8255 180)
			(size 0.4064 1.2192)
			(layers "B.Cu" "B.Mask" "B.Paste")
			(net "GND")
		)
		(pad "4" smd rect
			(at 0.65024 0.8255 180)
			(size 0.4064 1.2192)
			(layers "B.Cu" "B.Mask" "B.Paste")
			(net "SSD_PERST_Y4")
		)
		(pad "5" smd rect
			(at -0.65024 0.8255 180)
			(size 0.4064 1.2192)
			(layers "B.Cu" "B.Mask" "B.Paste")
			(net "P3V3_STBY")
		)
	)
	(footprint ""
		(layer "B.Cu")
		(at 246.126 -72.009 90)
		(property "Reference" "C517"
			(at 0 0 90)
			(layer "B.SilkS")
			(hide yes)
			(effects
				(font
					(size 1.27 1.27)
				)
				(justify mirror)
			)
		)
		(property "Value" "SC4D7U16V5KX-1-GP"
			(at 0.0762 -6.1214 90)
			(unlocked yes)
			(layer "B.Fab")
			(hide yes)
			(effects
				(font
					(size 1.016 1.016)
					(thickness 0.1524)
				)
				(justify mirror)
			)
		)
		(property "Device Type" "C805H56"
			(at 0.0762 -8.1534 90)
			(unlocked yes)
			(layer "B.Fab")
			(hide yes)
			(effects
				(font
					(size 1.016 1.016)
					(thickness 0.1524)
				)
				(justify mirror)
			)
		)
		(duplicate_pad_numbers_are_jumpers no)
		(fp_line
			(start -0.635 0)
			(end 0.635 0)
			(stroke
				(width 0.508)
				(type default)
			)
			(layer "B.SilkS")
		)
		(fp_rect
			(start 0.9652 1.778)
			(end -0.9652 -1.778)
			(stroke
				(width 0)
				(type default)
			)
			(fill no)
			(layer "B.CrtYd")
		)
		(fp_poly
			(pts
				(xy 0.9652 -1.778) (xy -0.9652 -1.778) (xy -0.9652 1.778) (xy 0.9652 1.778)
			)
			(stroke
				(width 0)
				(type default)
			)
			(fill no)
			(layer "B.Fab")
		)
		(pad "1" smd rect
			(at 0 -0.9652 270)
			(size 1.397 1.143)
			(layers "B.Cu" "B.Mask" "B.Paste")
			(net "DUT_AVD_TX")
		)
		(pad "2" smd rect
			(at 0 0.9652 270)
			(size 1.397 1.143)
			(layers "B.Cu" "B.Mask" "B.Paste")
			(net "GND")
		)
	)
	(footprint ""
		(layer "B.Cu")
		(at 53.721 -132.461 -90)
		(property "Reference" "R318"
			(at 0 0 90)
			(layer "B.SilkS")
			(hide yes)
			(effects
				(font
					(size 1.27 1.27)
				)
				(justify mirror)
			)
		)
		(property "Value" "0R2J-2-GP"
			(at -0.064008 -3.993896 270)
			(unlocked yes)
			(layer "B.Fab")
			(hide yes)
			(effects
				(font
					(size 1.016 1.016)
					(thickness 0.1524)
				)
				(justify mirror)
			)
		)
		(property "Device Type" "R402H16"
			(at -0.064008 -5.517896 270)
			(unlocked yes)
			(layer "B.Fab")
			(hide yes)
			(effects
				(font
					(size 1.016 1.016)
					(thickness 0.1524)
				)
				(justify mirror)
			)
		)
		(duplicate_pad_numbers_are_jumpers no)
		(fp_line
			(start -0.508 -0.9398)
			(end 0.508 -0.9398)
			(stroke
				(width 0.1524)
				(type default)
			)
			(layer "B.SilkS")
		)
		(fp_line
			(start 0.508 -0.9398)
			(end 0.508 0.9398)
			(stroke
				(width 0.1524)
				(type default)
			)
			(layer "B.SilkS")
		)
		(fp_rect
			(start 0.508 0.9398)
			(end -0.508 -0.9398)
			(stroke
				(width 0)
				(type default)
			)
			(fill no)
			(layer "B.CrtYd")
		)
		(fp_rect
			(start 0.508 0.9398)
			(end -0.508 -0.9398)
			(stroke
				(width 0)
				(type default)
			)
			(fill no)
			(layer "B.Fab")
		)
		(pad "1" smd custom
			(at 0 -0.4445 90)
			(size 0.1397 0.1397)
			(layers "B.Cu" "B.Mask" "B.Paste")
			(net "ADC_P3V3_STBY")
			(options
				(clearance outline)
				(anchor circle)
			)
			(primitives
				(gr_poly
					(pts
						(arc
							(start -0.1778 0.2794)
							(mid -0.249642 0.249642)
							(end -0.2794 0.1778)
						)
						(arc
							(start -0.2794 -0.1778)
							(mid -0.249642 -0.249642)
							(end -0.1778 -0.2794)
						)
						(arc
							(start 0.1778 -0.2794)
							(mid 0.249642 -0.249642)
							(end 0.2794 -0.1778)
						)
						(arc
							(start 0.2794 0.1778)
							(mid 0.249642 0.249642)
							(end 0.1778 0.2794)
						)
					)
					(width 0)
					(fill yes)
				)
			)
		)
		(pad "2" smd custom
			(at 0 0.4445 90)
			(size 0.1397 0.1397)
			(layers "B.Cu" "B.Mask" "B.Paste")
			(net "ADC_P3V3_STBY_BMC")
			(options
				(clearance outline)
				(anchor circle)
			)
			(primitives
				(gr_poly
					(pts
						(arc
							(start -0.1778 0.2794)
							(mid -0.249642 0.249642)
							(end -0.2794 0.1778)
						)
						(arc
							(start -0.2794 -0.1778)
							(mid -0.249642 -0.249642)
							(end -0.1778 -0.2794)
						)
						(arc
							(start 0.1778 -0.2794)
							(mid 0.249642 -0.249642)
							(end 0.2794 -0.1778)
						)
						(arc
							(start 0.2794 0.1778)
							(mid 0.249642 0.249642)
							(end 0.1778 0.2794)
						)
					)
					(width 0)
					(fill yes)
				)
			)
		)
	)
	(footprint ""
		(layer "B.Cu")
		(at 332.7654 -184.8866)
		(property "Reference" "R573"
			(at 0 0 0)
			(layer "B.SilkS")
			(hide yes)
			(effects
				(font
					(size 1.27 1.27)
				)
				(justify mirror)
			)
		)
		(property "Value" "10KR2F-2-GP"
			(at -0.064008 -3.993896 0)
			(unlocked yes)
			(layer "B.Fab")
			(hide yes)
			(effects
				(font
					(size 1.016 1.016)
					(thickness 0.1524)
				)
				(justify mirror)
			)
		)
		(property "Device Type" "R402H16"
			(at -0.064008 -5.517896 0)
			(unlocked yes)
			(layer "B.Fab")
			(hide yes)
			(effects
				(font
					(size 1.016 1.016)
					(thickness 0.1524)
				)
				(justify mirror)
			)
		)
		(duplicate_pad_numbers_are_jumpers no)
		(fp_line
			(start -0.508 -0.9398)
			(end 0.508 -0.9398)
			(stroke
				(width 0.1524)
				(type default)
			)
			(layer "B.SilkS")
		)
		(fp_line
			(start 0.508 -0.9398)
			(end 0.508 0.9398)
			(stroke
				(width 0.1524)
				(type default)
			)
			(layer "B.SilkS")
		)
		(fp_rect
			(start 0.508 0.9398)
			(end -0.508 -0.9398)
			(stroke
				(width 0)
				(type default)
			)
			(fill no)
			(layer "B.CrtYd")
		)
		(fp_rect
			(start 0.508 0.9398)
			(end -0.508 -0.9398)
			(stroke
				(width 0)
				(type default)
			)
			(fill no)
			(layer "B.Fab")
		)
		(pad "1" smd custom
			(at 0 -0.4445 180)
			(size 0.1397 0.1397)
			(layers "B.Cu" "B.Mask" "B.Paste")
			(net "P3V3_STBY")
			(options
				(clearance outline)
				(anchor circle)
			)
			(primitives
				(gr_poly
					(pts
						(arc
							(start -0.1778 0.2794)
							(mid -0.249642 0.249642)
							(end -0.2794 0.1778)
						)
						(arc
							(start -0.2794 -0.1778)
							(mid -0.249642 -0.249642)
							(end -0.1778 -0.2794)
						)
						(arc
							(start 0.1778 -0.2794)
							(mid 0.249642 -0.249642)
							(end 0.2794 -0.1778)
						)
						(arc
							(start 0.2794 0.1778)
							(mid 0.249642 0.249642)
							(end 0.1778 0.2794)
						)
					)
					(width 0)
					(fill yes)
				)
			)
		)
		(pad "2" smd custom
			(at 0 0.4445 180)
			(size 0.1397 0.1397)
			(layers "B.Cu" "B.Mask" "B.Paste")
			(net "IOEXP4_AD0")
			(options
				(clearance outline)
				(anchor circle)
			)
			(primitives
				(gr_poly
					(pts
						(arc
							(start -0.1778 0.2794)
							(mid -0.249642 0.249642)
							(end -0.2794 0.1778)
						)
						(arc
							(start -0.2794 -0.1778)
							(mid -0.249642 -0.249642)
							(end -0.1778 -0.2794)
						)
						(arc
							(start 0.1778 -0.2794)
							(mid 0.249642 -0.249642)
							(end 0.2794 -0.1778)
						)
						(arc
							(start 0.2794 0.1778)
							(mid 0.249642 0.249642)
							(end 0.1778 0.2794)
						)
					)
					(width 0)
					(fill yes)
				)
			)
		)
	)
)
